# S9S_MB_2U (Grand Teton) — schematic netlist excerpt (pin names and nets, part order shuffled) for the footprints in the layout excerpt that follows; sources: Cadence DE-HDL packaged netlist, KiCad conversion of 03242023_DA0F0TMBIJ0_F0T_Motherboard_J_brd_V01_OCP.brd

R2847  Q_RES  33.2 1% CHIP  pkg 0402LF  page 213 : A = RST_BMC_FROM_SWB_ISO_N ; B = RST_BMC_FROM_SWB_ISO_R_N
C279  Q_CAP  22UF 4V 20% X6S  pkg C0402  page 77 : A = PVCCIN_CPU1 ; B = GND

(kicad_pcb
	(version 20260206)
	(generator "pcbnew")
	(generator_version "10.0")
	(general
		(thickness 1.6)
		(legacy_teardrops no)
	)
	(paper "A4")
	(title_block
		(title "03242023_DA0F0TMBIJ0_F0T_Motherboard_J_brd_V01_OCP.brd")
		(comment 1 "Grand Teton / footprints 1886-1887 of 6105")
	)
	(layers
		(0 "F.Cu" signal "TOP")
		(4 "In1.Cu" signal "GND")
		(6 "In2.Cu" signal "IN1")
		(8 "In3.Cu" signal "GND1")
		(10 "In4.Cu" signal "IN2")
		(12 "In5.Cu" signal "GND2")
		(14 "In6.Cu" signal "IN3")
		(16 "In7.Cu" signal "GND3")
		(18 "In8.Cu" signal "VCC")
		(20 "In9.Cu" signal "VCC1")
		(22 "In10.Cu" signal "GND4")
		(24 "In11.Cu" signal "IN4")
		(26 "In12.Cu" signal "GND5")
		(28 "In13.Cu" signal "IN5")
		(30 "In14.Cu" signal "GND6")
		(32 "In15.Cu" signal "IN6")
		(34 "In16.Cu" signal "GND7")
		(2 "B.Cu" signal "BOTTOM")
		(9 "F.Adhes" user "F.Adhesive")
		(11 "B.Adhes" user "B.Adhesive")
		(13 "F.Paste" user "Package Geometry/Pastemask Top")
		(15 "B.Paste" user "Package Geometry/Pastemask Bottom")
		(5 "F.SilkS" user "Ref Des/Silkscreen Top")
		(7 "B.SilkS" user "Ref Des/Silkscreen Bottom")
		(1 "F.Mask" user "Board Geometry/Soldermask Top")
		(3 "B.Mask" user "Board Geometry/Soldermask Bottom")
		(17 "Dwgs.User" user "User.Drawings")
		(19 "Cmts.User" user "User.Comments")
		(21 "Eco1.User" user "User.Eco1")
		(23 "Eco2.User" user "User.Eco2")
		(25 "Edge.Cuts" user "Board Geometry/Outline")
		(27 "Margin" user)
		(31 "F.CrtYd" user "Package Geometry/Place Bound Top")
		(29 "B.CrtYd" user "Package Geometry/Place Bound Bottom")
		(35 "F.Fab" user "Ref Des/Assembly Top")
		(33 "B.Fab" user "Ref Des/Assembly Bottom")
	)
	(footprint ""
		(layer "F.Cu")
		(at 160.83788 -109.565948)
		(property "Reference" "R2847"
			(at 0 0 0)
			(layer "F.SilkS")
			(hide yes)
			(effects
				(font
					(size 1.27 1.27)
				)
			)
		)
		(property "Value" ""
			(at 0 0 0)
			(layer "F.Fab")
			(effects
				(font
					(size 1.27 1.27)
				)
			)
		)
		(duplicate_pad_numbers_are_jumpers no)
		(fp_line
			(start -0.7874 -0.4064)
			(end 0.7874 -0.4064)
			(stroke
				(width 0.1524)
				(type default)
			)
			(layer "F.SilkS")
		)
		(fp_line
			(start -0.7874 0.4064)
			(end -0.7874 -0.4064)
			(stroke
				(width 0.1524)
				(type default)
			)
			(layer "F.SilkS")
		)
		(fp_line
			(start 0.7874 -0.4064)
			(end 0.7874 0.4064)
			(stroke
				(width 0.1524)
				(type default)
			)
			(layer "F.SilkS")
		)
		(fp_line
			(start 0.7874 0.4064)
			(end -0.7874 0.4064)
			(stroke
				(width 0.1524)
				(type default)
			)
			(layer "F.SilkS")
		)
		(fp_line
			(start -0.67945 -0.305054)
			(end -0.12065 -0.305054)
			(stroke
				(width 0.1)
				(type default)
			)
			(layer "F.Fab")
		)
		(fp_line
			(start -0.67945 0.3048)
			(end -0.67945 -0.305054)
			(stroke
				(width 0.1)
				(type default)
			)
			(layer "F.Fab")
		)
		(fp_line
			(start -0.12065 -0.305054)
			(end -0.12065 -0.2794)
			(stroke
				(width 0.1)
				(type default)
			)
			(layer "F.Fab")
		)
		(fp_line
			(start -0.12065 -0.2794)
			(end 0.12065 -0.2794)
			(stroke
				(width 0.1)
				(type default)
			)
			(layer "F.Fab")
		)
		(fp_line
			(start -0.12065 0.2794)
			(end -0.12065 0.3048)
			(stroke
				(width 0.1)
				(type default)
			)
			(layer "F.Fab")
		)
		(fp_line
			(start -0.12065 0.3048)
			(end -0.67945 0.3048)
			(stroke
				(width 0.1)
				(type default)
			)
			(layer "F.Fab")
		)
		(fp_line
			(start 0.120396 0.2794)
			(end -0.12065 0.2794)
			(stroke
				(width 0.1)
				(type default)
			)
			(layer "F.Fab")
		)
		(fp_line
			(start 0.120396 0.3048)
			(end 0.120396 0.2794)
			(stroke
				(width 0.1)
				(type default)
			)
			(layer "F.Fab")
		)
		(fp_line
			(start 0.12065 -0.3048)
			(end 0.67945 -0.3048)
			(stroke
				(width 0.1)
				(type default)
			)
			(layer "F.Fab")
		)
		(fp_line
			(start 0.12065 -0.2794)
			(end 0.12065 -0.3048)
			(stroke
				(width 0.1)
				(type default)
			)
			(layer "F.Fab")
		)
		(fp_line
			(start 0.67945 -0.3048)
			(end 0.67945 0.3048)
			(stroke
				(width 0.1)
				(type default)
			)
			(layer "F.Fab")
		)
		(fp_line
			(start 0.67945 0.3048)
			(end 0.120396 0.3048)
			(stroke
				(width 0.1)
				(type default)
			)
			(layer "F.Fab")
		)
		(pad "1" smd circle
			(at -0.40005 0)
			(size 0 0)
			(layers "F.Cu" "F.Mask" "F.Paste")
			(net "RST_BMC_FROM_SWB_ISO_N")
		)
		(pad "2" smd circle
			(at 0.40005 0)
			(size 0 0)
			(layers "F.Cu" "F.Mask" "F.Paste")
			(net "RST_BMC_FROM_SWB_ISO_R_N")
		)
	)
	(footprint ""
		(layer "F.Cu")
		(at 107.2769 -255.0541 90)
		(property "Reference" "C279"
			(at 0 0 90)
			(layer "F.SilkS")
			(hide yes)
			(effects
				(font
					(size 1.27 1.27)
				)
			)
		)
		(property "Value" ""
			(at 0 0 90)
			(layer "F.Fab")
			(effects
				(font
					(size 1.27 1.27)
				)
			)
		)
		(duplicate_pad_numbers_are_jumpers no)
		(fp_line
			(start 0.7874 -0.4064)
			(end 0.7874 0.4064)
			(stroke
				(width 0.1524)
				(type default)
			)
			(layer "F.SilkS")
		)
		(fp_line
			(start -0.7874 -0.4064)
			(end 0.7874 -0.4064)
			(stroke
				(width 0.1524)
				(type default)
			)
			(layer "F.SilkS")
		)
		(fp_line
			(start 0.7874 0.4064)
			(end -0.7874 0.4064)
			(stroke
				(width 0.1524)
				(type default)
			)
			(layer "F.SilkS")
		)
		(fp_line
			(start -0.7874 0.4064)
			(end -0.7874 -0.4064)
			(stroke
				(width 0.1524)
				(type default)
			)
			(layer "F.SilkS")
		)
		(fp_line
			(start -0.12065 -0.305054)
			(end -0.12065 -0.2794)
			(stroke
				(width 0.1)
				(type default)
			)
			(layer "F.Fab")
		)
		(fp_line
			(start -0.67945 -0.305054)
			(end -0.12065 -0.305054)
			(stroke
				(width 0.1)
				(type default)
			)
			(layer "F.Fab")
		)
		(fp_line
			(start 0.67945 -0.3048)
			(end 0.67945 0.3048)
			(stroke
				(width 0.1)
				(type default)
			)
			(layer "F.Fab")
		)
		(fp_line
			(start 0.12065 -0.3048)
			(end 0.67945 -0.3048)
			(stroke
				(width 0.1)
				(type default)
			)
			(layer "F.Fab")
		)
		(fp_line
			(start 0.12065 -0.2794)
			(end 0.12065 -0.3048)
			(stroke
				(width 0.1)
				(type default)
			)
			(layer "F.Fab")
		)
		(fp_line
			(start -0.12065 -0.2794)
			(end 0.12065 -0.2794)
			(stroke
				(width 0.1)
				(type default)
			)
			(layer "F.Fab")
		)
		(fp_line
			(start 0.120396 0.2794)
			(end -0.12065 0.2794)
			(stroke
				(width 0.1)
				(type default)
			)
			(layer "F.Fab")
		)
		(fp_line
			(start -0.12065 0.2794)
			(end -0.12065 0.3048)
			(stroke
				(width 0.1)
				(type default)
			)
			(layer "F.Fab")
		)
		(fp_line
			(start 0.67945 0.3048)
			(end 0.120396 0.3048)
			(stroke
				(width 0.1)
				(type default)
			)
			(layer "F.Fab")
		)
		(fp_line
			(start 0.120396 0.3048)
			(end 0.120396 0.2794)
			(stroke
				(width 0.1)
				(type default)
			)
			(layer "F.Fab")
		)
		(fp_line
			(start -0.12065 0.3048)
			(end -0.67945 0.3048)
			(stroke
				(width 0.1)
				(type default)
			)
			(layer "F.Fab")
		)
		(fp_line
			(start -0.67945 0.3048)
			(end -0.67945 -0.305054)
			(stroke
				(width 0.1)
				(type default)
			)
			(layer "F.Fab")
		)
		(pad "1" smd circle
			(at -0.40005 0 90)
			(size 0 0)
			(layers "F.Cu" "F.Mask" "F.Paste")
			(net "PVCCIN_CPU1")
		)
		(pad "2" smd circle
			(at 0.40005 0 90)
			(size 0 0)
			(layers "F.Cu" "F.Mask" "F.Paste")
			(net "GND")
		)
	)
)
